FILE_TYPE = CONNECTIVITY;
{Allegro Design Entry HDL 17.4-2019 S026 (4007227) 1/17/2022}
"PAGE_NUMBER" = 254;
0"NC";
1"P3V3_AUX\g";
2"GND\g";
3"GND\g";
4"P3V3_AUX\g";
5"P3V3_AUX\g";
6"GND\g";
7"GND\g";
8"GND\g";
9"P3V3_AUX\g";
10"P3V3_AUX\g";
11"GND\g";
12"GND\g";
13"P5V\g";
14"P3V3\g";
15"LED_PWRGD_P1V2_AUX_D";
16"PWRGD_P1V2_AUX_R";
17"LED_PWRGD_P1V2_AUX";
18"LED_PWRGD_P1V8_AUX";
19"LED_PWRGD_P1V8_AUX_D";
20"PWRGD_P1V8_AUX_R";
21"LED_PWRGD_SYS_PWROK_R";
22"LED_PWRGD_PS_PWROK_PLD";
23"LED_RST_RSMRST_PLD_R_N";
24"PWRGD_PS_PWROK_PLD";
25"RST_CPU0_RSMRST_N";
26"SCM_SYS_PWROK_R2";
27"LED_RST_RSMRST_PLD_R_N_D";
28"LED_PWRGD_SYS_PWROK_R_D";
29"LED_PWRGD_PS_PWROK_PLD_D";
30"LED_P3V3";
31"LED_P5V";
%"UNIVERSAL_POWER"
"1","(-500,1200)","0","pure_quanta_power","I10";
;
HDL_POWER"P3V3"
CDS_LIB"pure_quanta_power";
"A"14;
%"UNIVERSAL_POWER"
"1","(-550,2450)","0","pure_quanta_power","I11";
;
HDL_POWER"P5V"
CDS_LIB"pure_quanta_power";
"A"13;
%"Q_LED"
"1","(-6675,5925)","2","pure_quanta","I14";
;
LOCATION"D96"
$SEC"1"
CDS_SEC"1"
PACK_TYPE"SMLF"
COLOR"LED_BLUE"
MATERIAL"IC"
MANUF_PN"LTST-C281TBKT-5A"
CDS_LIB"pure_quanta"
NEEDS_NO_SIZE"TRUE"
PART_NUMBER"BEBL0172Z00";
"A"
$PN"A"22;
"C"
$PN"C"29;
%"Q_RES"
"1","(-5375,5925)","0","pure_quanta","I15";
;
LOCATION"R3075"
$SEC"1"
CDS_SEC"1"
TOLERANCE"1%"
VALUE"130"
MATERIAL"CHIP"
WATTAGE"1/16W"
PACK_TYPE"0402LF"
CDS_LIB"pure_quanta"
PART_NUMBER"CS11302FB03";
"B"
$PN"2"1;
"A"
$PN"1"22;
%"UNIVERSAL_POWER"
"1","(-4725,6075)","0","pure_quanta_power","I16";
;
HDL_POWER"P3V3_AUX"
CDS_LIB"pure_quanta_power";
"A"1;
%"Q_LED"
"1","(-2050,2200)","2","pure_quanta","I17";
;
LOCATION"D98"
$SEC"1"
CDS_SEC"1"
MANUF_PN"LTST-C281TBKT-5A"
MATERIAL"IC"
PACK_TYPE"SMLF"
COLOR"LED_BLUE"
CDS_LIB"pure_quanta"
NEEDS_NO_SIZE"TRUE"
PART_NUMBER"BEBL0172Z00";
"A"
$PN"A"31;
"C"
$PN"C"8;
%"MOSFET_NCH_DUAL"
"2","(-7750,5650)","0","pure_quanta","I18";
;
LOCATION"Q78"
SEC"2"
VALUE"PJT138K"
MATERIAL"IC"
PART_TYPE"SMLF"
SEC_TYPE""
CDS_LIB"pure_quanta"
NEEDS_NO_SIZE"TRUE"
CDS_LMAN_SYM_OUTLINE"-150,150,150,-150"
PART_NUMBER"BAM138K0003";
"S2"
$PN"4"12;
"G2"
$PN"5"24;
"D2"
$PN"3"29;
%"UNIVERSAL_GND"
"1","(-2725,725)","0","pure_quanta_power","I2";
;
CDS_LIB"pure_quanta_power"
HDL_POWER"GND";
"A"2;
%"UNIVERSAL_GND"
"1","(-7625,3925)","0","pure_quanta_power","I20";
;
CDS_LIB"pure_quanta_power"
HDL_POWER"GND";
"A"3;
%"Q_RES"
"1","(-5250,4550)","0","pure_quanta","I21";
;
LOCATION"R3071"
$SEC"1"
CDS_SEC"1"
PACK_TYPE"0402LF"
TOLERANCE"1%"
VALUE"130"
MATERIAL"CHIP"
WATTAGE"1/16W"
CDS_LIB"pure_quanta"
PART_NUMBER"CS11302FB03";
"B"
$PN"2"4;
"A"
$PN"1"18;
%"UNIVERSAL_POWER"
"1","(-4600,4700)","0","pure_quanta_power","I22";
;
HDL_POWER"P3V3_AUX"
CDS_LIB"pure_quanta_power";
"A"4;
%"Q_LED"
"1","(-6600,4550)","2","pure_quanta","I23";
;
LOCATION"D91"
$SEC"1"
CDS_SEC"1"
PACK_TYPE"SMLF"
MATERIAL"IC"
MANUF_PN"LTST-C281TBKT-5A"
COLOR"LED_BLUE"
CDS_LIB"pure_quanta"
NEEDS_NO_SIZE"TRUE"
PART_NUMBER"BEBL0172Z00";
"A"
$PN"A"18;
"C"
$PN"C"19;
%"MOSFET_NCH_DUAL"
"1","(-7675,4275)","0","pure_quanta","I24";
;
LOCATION"Q78"
$SEC"1"
CDS_SEC"1"
MATERIAL"IC"
VALUE"PJT138K"
PART_TYPE"SMLF"
NEEDS_NO_SIZE"TRUE"
CDS_LMAN_SYM_OUTLINE"-150,150,150,-150"
CDS_LIB"pure_quanta"
PART_NUMBER"BAM138K0003";
"D1"
$PN"6"19;
"G1"
$PN"2"20;
"S1"
$PN"1"3;
%"Q_LED"
"1","(-2125,975)","2","pure_quanta","I3";
;
LOCATION"D99"
$SEC"1"
CDS_SEC"1"
MANUF_PN"LTST-C281TBKT-5A"
MATERIAL"IC"
PACK_TYPE"SMLF"
COLOR"LED_BLUE"
NEEDS_NO_SIZE"TRUE"
CDS_LIB"pure_quanta"
PART_NUMBER"BEBL0172Z00";
"A"
$PN"A"30;
"C"
$PN"C"2;
%"UNIVERSAL_POWER"
"1","(-4725,1675)","0","pure_quanta_power","I31";
;
HDL_POWER"P3V3_AUX"
CDS_LIB"pure_quanta_power";
"A"5;
%"Q_RES"
"1","(-5375,1475)","0","pure_quanta","I32";
;
LOCATION"R3069"
$SEC"1"
CDS_SEC"1"
TOLERANCE"1%"
PACK_TYPE"0402LF"
MATERIAL"CHIP"
WATTAGE"1/16W"
VALUE"130"
CDS_LIB"pure_quanta"
PART_NUMBER"CS11302FB03";
"B"
$PN"2"5;
"A"
$PN"1"21;
%"Q_LED"
"1","(-6675,1475)","2","pure_quanta","I33";
;
LOCATION"D88"
$SEC"1"
CDS_SEC"1"
PACK_TYPE"SMLF"
MATERIAL"IC"
MANUF_PN"LTST-C281TBKT-5A"
COLOR"LED_BLUE"
CDS_LIB"pure_quanta"
NEEDS_NO_SIZE"TRUE"
PART_NUMBER"BEBL0172Z00";
"A"
$PN"A"21;
"C"
$PN"C"28;
%"UNIVERSAL_GND"
"1","(-7700,850)","0","pure_quanta_power","I34";
;
CDS_LIB"pure_quanta_power"
HDL_POWER"GND";
"A"6;
%"MOSFET_NCH_DUAL"
"2","(-7750,1200)","0","pure_quanta","I35";
;
LOCATION"Q87"
SEC"2"
VALUE"PJT138K"
MATERIAL"IC"
PART_TYPE"SMLF"
CDS_LMAN_SYM_OUTLINE"-150,150,150,-150"
CDS_LIB"pure_quanta"
SEC_TYPE""
NEEDS_NO_SIZE"TRUE"
PART_NUMBER"BAM138K0003";
"S2"
$PN"4"6;
"G2"
$PN"5"26;
"D2"
$PN"3"28;
%"MOSFET_NCH_DUAL"
"1","(-7700,2850)","0","pure_quanta","I38";
;
LOCATION"Q87"
$SEC"1"
CDS_SEC"1"
PART_TYPE"SMLF"
MATERIAL"IC"
VALUE"PJT138K"
NEEDS_NO_SIZE"TRUE"
CDS_LMAN_SYM_OUTLINE"-150,150,150,-150"
CDS_LIB"pure_quanta"
PART_NUMBER"BAM138K0003";
"D1"
$PN"6"27;
"G1"
$PN"2"25;
"S1"
$PN"1"7;
%"UNIVERSAL_GND"
"1","(-7650,2500)","0","pure_quanta_power","I39";
;
CDS_LIB"pure_quanta_power"
HDL_POWER"GND";
"A"7;
%"UNIVERSAL_GND"
"1","(-2650,1950)","0","pure_quanta_power","I4";
;
CDS_LIB"pure_quanta_power"
HDL_POWER"GND";
"A"8;
%"Q_LED"
"1","(-6625,3125)","2","pure_quanta","I40";
;
LOCATION"D93"
$SEC"1"
CDS_SEC"1"
MATERIAL"IC"
COLOR"LED_BLUE"
PACK_TYPE"SMLF"
MANUF_PN"LTST-C281TBKT-5A"
NEEDS_NO_SIZE"TRUE"
CDS_LIB"pure_quanta"
PART_NUMBER"BEBL0172Z00";
"A"
$PN"A"23;
"C"
$PN"C"27;
%"Q_RES"
"1","(-5200,3125)","0","pure_quanta","I41";
;
LOCATION"R3074"
$SEC"1"
CDS_SEC"1"
PACK_TYPE"0402LF"
MATERIAL"CHIP"
VALUE"130"
WATTAGE"1/16W"
TOLERANCE"1%"
CDS_LIB"pure_quanta"
PART_NUMBER"CS11302FB03";
"B"
$PN"2"9;
"A"
$PN"1"23;
%"UNIVERSAL_POWER"
"1","(-4600,3300)","0","pure_quanta_power","I42";
;
HDL_POWER"P3V3_AUX"
CDS_LIB"pure_quanta_power";
"A"9;
%"Q_LED"
"1","(-1875,3950)","2","pure_quanta","I43";
;
LOCATION"D6000"
$SEC"1"
CDS_SEC"1"
PACK_TYPE"SMLF"
MATERIAL"IC"
MANUF_PN"LTST-C281TBKT-5A"
COLOR"LED_BLUE"
NEEDS_NO_SIZE"TRUE"
CDS_LIB"pure_quanta"
PART_NUMBER"BEBL0172Z00";
"A"
$PN"A"17;
"C"
$PN"C"15;
%"UNIVERSAL_POWER"
"1","(-250,4075)","0","pure_quanta_power","I44";
;
HDL_POWER"P3V3_AUX"
CDS_LIB"pure_quanta_power";
"A"10;
%"Q_RES"
"1","(-775,3950)","0","pure_quanta","I45";
;
LOCATION"R6246"
$SEC"1"
CDS_SEC"1"
PACK_TYPE"0402LF"
TOLERANCE"1%"
VALUE"130"
MATERIAL"CHIP"
WATTAGE"1/16W"
CDS_LIB"pure_quanta"
PART_NUMBER"CS11302FB03";
"B"
$PN"2"10;
"A"
$PN"1"17;
%"UNIVERSAL_GND"
"1","(-2825,3325)","0","pure_quanta_power","I46";
;
CDS_LIB"pure_quanta_power"
HDL_POWER"GND";
"A"11;
%"MOSFET_NCH_DUAL"
"1","(-2875,3675)","0","pure_quanta","I47";
;
LOCATION"Q6000"
$SEC"1"
CDS_SEC"1"
MATERIAL"IC"
VALUE"PJT138K"
PART_TYPE"SMLF"
NEEDS_NO_SIZE"TRUE"
CDS_LMAN_SYM_OUTLINE"-150,150,150,-150"
CDS_LIB"pure_quanta"
PART_NUMBER"BAM138K0003";
"D1"
$PN"6"15;
"G1"
$PN"2"16;
"S1"
$PN"1"11;
%"UNIVERSAL_GND"
"1","(-7700,5300)","0","pure_quanta_power","I5";
;
CDS_LIB"pure_quanta_power"
HDL_POWER"GND";
"A"12;
%"Q_RES"
"1","(-1025,975)","0","pure_quanta","I8";
;
LOCATION"R3100"
$SEC"1"
CDS_SEC"1"
PACK_TYPE"0402LF"
MATERIAL"CHIP"
TOLERANCE"1%"
VALUE"130"
WATTAGE"1/16W"
CDS_LIB"pure_quanta"
PART_NUMBER"CS11302FB03";
"B"
$PN"2"14;
"A"
$PN"1"30;
%"Q_RES"
"1","(-950,2200)","0","pure_quanta","I9";
;
LOCATION"R3102"
$SEC"1"
CDS_SEC"1"
VALUE"470"
MATERIAL"CHIP"
WATTAGE"1/16W"
PACK_TYPE"0402LF"
TOLERANCE"1%"
CDS_LIB"pure_quanta"
PART_NUMBER"CS14702FB04";
"B"
$PN"2"13;
"A"
$PN"1"31;
END.
